(kicad_pcb
	(version 20260206)
	(generator "pcbnew")
	(generator_version "10.0")
	(general
		(thickness 1.6)
		(legacy_teardrops no)
	)
	(paper "A4")
	(title_block
		(title "fcb — 12433-1M.1206WZS1330.brd")
		(comment 1 "Open Vault / Knox (Wiwynn) / footprints 230-233 of 495")
	)
	(layers
		(0 "F.Cu" signal "TOP")
		(4 "In1.Cu" signal "L2GND")
		(6 "In2.Cu" signal "L3VCC")
		(2 "B.Cu" signal "BOTTOM")
		(9 "F.Adhes" user "F.Adhesive")
		(11 "B.Adhes" user "B.Adhesive")
		(13 "F.Paste" user "Package Geometry/Pastemask Top")
		(15 "B.Paste" user "Package Geometry/Pastemask Bottom")
		(5 "F.SilkS" user "Ref Des/Silkscreen Top")
		(7 "B.SilkS" user "Ref Des/Silkscreen Bottom")
		(1 "F.Mask" user "Board Geometry/Soldermask Top")
		(3 "B.Mask" user "Board Geometry/Soldermask Bottom")
		(17 "Dwgs.User" user "User.Drawings")
		(19 "Cmts.User" user "User.Comments")
		(21 "Eco1.User" user "User.Eco1")
		(23 "Eco2.User" user "User.Eco2")
		(25 "Edge.Cuts" user "Board Geometry/Outline")
		(27 "Margin" user)
		(31 "F.CrtYd" user "Package Geometry/Place Bound Top")
		(29 "B.CrtYd" user "Package Geometry/Place Bound Bottom")
		(35 "F.Fab" user "Ref Des/Assembly Top")
		(33 "B.Fab" user "Ref Des/Assembly Bottom")
	)
	(footprint ""
		(layer "F.Cu")
		(at 19.6088 -178.8668 180)
		(property "Reference" "R91"
			(at 0 0 180)
			(layer "F.SilkS")
			(hide yes)
			(effects
				(font
					(size 1.27 1.27)
				)
			)
		)
		(property "Value" "10KR2F-2-GP"
			(at 0.064008 -3.993896 180)
			(unlocked yes)
			(layer "F.Fab")
			(hide yes)
			(effects
				(font
					(size 1.016 1.016)
					(thickness 0.1524)
				)
			)
		)
		(property "Device Type" "R402H16"
			(at 0.064008 -5.517896 180)
			(unlocked yes)
			(layer "F.Fab")
			(hide yes)
			(effects
				(font
					(size 1.016 1.016)
					(thickness 0.1524)
				)
			)
		)
		(duplicate_pad_numbers_are_jumpers no)
		(fp_line
			(start 0.508 -0.9398)
			(end -0.508 -0.9398)
			(stroke
				(width 0.1524)
				(type default)
			)
			(layer "F.SilkS")
		)
		(fp_line
			(start -0.508 -0.9398)
			(end -0.508 0.9398)
			(stroke
				(width 0.1524)
				(type default)
			)
			(layer "F.SilkS")
		)
		(fp_rect
			(start -0.508 0.9398)
			(end 0.508 -0.9398)
			(stroke
				(width 0)
				(type default)
			)
			(fill no)
			(layer "F.CrtYd")
		)
		(fp_rect
			(start -0.508 0.9398)
			(end 0.508 -0.9398)
			(stroke
				(width 0)
				(type default)
			)
			(fill no)
			(layer "F.Fab")
		)
		(pad "1" smd custom
			(at 0 -0.4445 180)
			(size 0.1397 0.1397)
			(layers "F.Cu" "F.Mask" "F.Paste")
			(net "FANIN_7")
			(options
				(clearance outline)
				(anchor circle)
			)
			(primitives
				(gr_poly
					(pts
						(arc
							(start -0.1778 -0.2794)
							(mid -0.249642 -0.249642)
							(end -0.2794 -0.1778)
						)
						(arc
							(start -0.2794 0.1778)
							(mid -0.249642 0.249642)
							(end -0.1778 0.2794)
						)
						(arc
							(start 0.1778 0.2794)
							(mid 0.249642 0.249642)
							(end 0.2794 0.1778)
						)
						(arc
							(start 0.2794 -0.1778)
							(mid 0.249642 -0.249642)
							(end 0.1778 -0.2794)
						)
					)
					(width 0)
					(fill yes)
				)
			)
		)
		(pad "2" smd custom
			(at 0 0.4445 180)
			(size 0.1397 0.1397)
			(layers "F.Cu" "F.Mask" "F.Paste")
			(net "GND")
			(options
				(clearance outline)
				(anchor circle)
			)
			(primitives
				(gr_poly
					(pts
						(arc
							(start -0.1778 -0.2794)
							(mid -0.249642 -0.249642)
							(end -0.2794 -0.1778)
						)
						(arc
							(start -0.2794 0.1778)
							(mid -0.249642 0.249642)
							(end -0.1778 0.2794)
						)
						(arc
							(start 0.1778 0.2794)
							(mid 0.249642 0.249642)
							(end 0.2794 0.1778)
						)
						(arc
							(start 0.2794 -0.1778)
							(mid 0.249642 -0.249642)
							(end 0.1778 -0.2794)
						)
					)
					(width 0)
					(fill yes)
				)
			)
		)
	)
	(footprint ""
		(layer "F.Cu")
		(at 20.0406 -383.8194)
		(property "Reference" "TC11"
			(at 0 0 0)
			(layer "F.SilkS")
			(hide yes)
			(effects
				(font
					(size 1.27 1.27)
				)
			)
		)
		(property "Value" "ST68U16VDM-1-GP"
			(at 0 -9.6012 0)
			(unlocked yes)
			(layer "F.Fab")
			(hide yes)
			(effects
				(font
					(size 1.016 1.016)
					(thickness 0.1524)
				)
			)
		)
		(property "Device Type" "CT7343H79"
			(at 0 -11.1252 0)
			(unlocked yes)
			(layer "F.Fab")
			(hide yes)
			(effects
				(font
					(size 1.016 1.016)
					(thickness 0.1524)
				)
			)
		)
		(duplicate_pad_numbers_are_jumpers no)
		(fp_line
			(start -2.286 -4.8768)
			(end -2.286 -2.032)
			(stroke
				(width 0.1524)
				(type default)
			)
			(layer "F.SilkS")
		)
		(fp_line
			(start -2.286 4.8768)
			(end -2.286 2.032)
			(stroke
				(width 0.1524)
				(type default)
			)
			(layer "F.SilkS")
		)
		(fp_line
			(start 2.1082 -4.699)
			(end -2.1082 -4.699)
			(stroke
				(width 0.508)
				(type default)
			)
			(layer "F.SilkS")
		)
		(fp_line
			(start 2.286 -4.8768)
			(end -2.286 -4.8768)
			(stroke
				(width 0.1524)
				(type default)
			)
			(layer "F.SilkS")
		)
		(fp_line
			(start 2.286 -2.032)
			(end 2.286 -4.8768)
			(stroke
				(width 0.1524)
				(type default)
			)
			(layer "F.SilkS")
		)
		(fp_line
			(start 2.286 2.032)
			(end 2.286 4.8768)
			(stroke
				(width 0.1524)
				(type default)
			)
			(layer "F.SilkS")
		)
		(fp_line
			(start 2.286 4.8768)
			(end -2.286 4.8768)
			(stroke
				(width 0.1524)
				(type default)
			)
			(layer "F.SilkS")
		)
		(fp_rect
			(start -2.1463 3.6449)
			(end 2.1463 -3.6449)
			(stroke
				(width 0)
				(type default)
			)
			(fill no)
			(layer "F.CrtYd")
		)
		(fp_poly
			(pts
				(xy -2.54 4.953) (xy -2.54 4.2926) (xy -3.81 4.2926) (xy -3.81 -4.2926) (xy -2.54 -4.2926) (xy -2.54 -4.953)
				(xy 2.54 -4.953) (xy 2.54 -4.2926) (xy 3.81 -4.2926) (xy 3.81 -1.6256) (xy 2.1463 -1.6256) (xy 2.1463 -3.6449)
				(xy -2.1463 -3.6449) (xy -2.1463 3.6449) (xy 2.1463 3.6449) (xy 2.1463 -1.6129) (xy 3.81 -1.6129)
				(xy 3.81 4.2926) (xy 2.54 4.2926) (xy 2.54 4.953)
			)
			(stroke
				(width 0)
				(type default)
			)
			(fill no)
			(layer "F.CrtYd")
		)
		(fp_rect
			(start -3.81 4.2926)
			(end -2.54 -4.2926)
			(stroke
				(width 0)
				(type default)
			)
			(fill no)
			(layer "F.Fab")
		)
		(fp_rect
			(start -2.54 4.953)
			(end 2.54 -4.953)
			(stroke
				(width 0)
				(type default)
			)
			(fill no)
			(layer "F.Fab")
		)
		(fp_rect
			(start 2.54 4.2926)
			(end 3.81 -4.2926)
			(stroke
				(width 0)
				(type default)
			)
			(fill no)
			(layer "F.Fab")
		)
		(pad "1" smd rect
			(at 0 -3.1496)
			(size 2.413 2.286)
			(layers "F.Cu" "F.Mask" "F.Paste")
			(net "P12V")
		)
		(pad "2" smd rect
			(at 0 3.1496)
			(size 2.413 2.286)
			(layers "F.Cu" "F.Mask" "F.Paste")
			(net "GND")
		)
		(zone
			(layer "F.Cu")
			(hatch none 0.5)
			(connect_pads
				(clearance 0)
			)
			(min_thickness 0.25)
			(keepout
				(tracks allowed)
				(vias not_allowed)
				(pads allowed)
				(copperpour not_allowed)
				(footprints allowed)
			)
			(placement
				(enabled no)
				(sheetname "")
			)
			(fill
				(thermal_gap 0.5)
				(thermal_bridge_width 0.5)
				(island_removal_mode 0)
			)
			(polygon
				(pts
					(xy 18.5293 -379.222) (xy 21.5519 -379.222) (xy 21.5519 -382.1176) (xy 21.5519 -382.4478) (xy 18.5293 -382.4478)
					(xy 18.5293 -382.1176)
				)
			)
		)
		(zone
			(layer "F.Cu")
			(hatch none 0.5)
			(connect_pads
				(clearance 0)
			)
			(min_thickness 0.25)
			(keepout
				(tracks allowed)
				(vias not_allowed)
				(pads allowed)
				(copperpour not_allowed)
				(footprints allowed)
			)
			(placement
				(enabled no)
				(sheetname "")
			)
			(fill
				(thermal_gap 0.5)
				(thermal_bridge_width 0.5)
				(island_removal_mode 0)
			)
			(polygon
				(pts
					(xy 21.5519 -385.5085) (xy 21.5519 -388.4168) (xy 18.5293 -388.4168) (xy 18.5293 -385.5212) (xy 18.5293 -385.191)
					(xy 21.5519 -385.191)
				)
			)
		)
	)
	(footprint ""
		(layer "F.Cu")
		(at 5.993384 -65.735962 180)
		(property "Reference" "Q3"
			(at 0 0 180)
			(layer "F.SilkS")
			(hide yes)
			(effects
				(font
					(size 1.27 1.27)
				)
			)
		)
		(property "Value" "PMBS3904-1-GP"
			(at 0 -9.0932 180)
			(unlocked yes)
			(layer "F.Fab")
			(hide yes)
			(effects
				(font
					(size 1.016 1.016)
					(thickness 0.1524)
				)
			)
		)
		(property "Device Type" "SOT-23-10H44"
			(at 0 -10.6172 180)
			(unlocked yes)
			(layer "F.Fab")
			(hide yes)
			(effects
				(font
					(size 1.016 1.016)
					(thickness 0.1524)
				)
			)
		)
		(duplicate_pad_numbers_are_jumpers no)
		(fp_line
			(start 1.651 1.778)
			(end 1.651 -1.778)
			(stroke
				(width 0.1524)
				(type default)
			)
			(layer "F.SilkS")
		)
		(fp_line
			(start 1.651 -1.778)
			(end -1.651 -1.778)
			(stroke
				(width 0.1524)
				(type default)
			)
			(layer "F.SilkS")
		)
		(fp_line
			(start -0.635 1.8796)
			(end -1.7526 1.8796)
			(stroke
				(width 0.3302)
				(type default)
			)
			(layer "F.SilkS")
		)
		(fp_line
			(start -0.71628 2.15265)
			(end -1.26492 2.15265)
			(stroke
				(width 0.0127)
				(type default)
			)
			(layer "F.SilkS")
		)
		(fp_line
			(start -0.719074 2.145538)
			(end -1.265936 2.14122)
			(stroke
				(width 0.0127)
				(type default)
			)
			(layer "F.SilkS")
		)
		(fp_line
			(start -0.9906 1.86309)
			(end -0.701294 2.15265)
			(stroke
				(width 0.0127)
				(type default)
			)
			(layer "F.SilkS")
		)
		(fp_line
			(start -0.994156 1.8669)
			(end -0.987044 1.8669)
			(stroke
				(width 0.0127)
				(type default)
			)
			(layer "F.SilkS")
		)
		(fp_line
			(start -1.003808 1.876552)
			(end -0.977646 1.876552)
			(stroke
				(width 0.0127)
				(type default)
			)
			(layer "F.SilkS")
		)
		(fp_line
			(start -1.013206 1.88595)
			(end -0.967994 1.88595)
			(stroke
				(width 0.0127)
				(type default)
			)
			(layer "F.SilkS")
		)
		(fp_line
			(start -1.022858 1.895602)
			(end -0.958596 1.895602)
			(stroke
				(width 0.0127)
				(type default)
			)
			(layer "F.SilkS")
		)
		(fp_line
			(start -1.032256 1.905)
			(end -0.948944 1.905)
			(stroke
				(width 0.0127)
				(type default)
			)
			(layer "F.SilkS")
		)
		(fp_line
			(start -1.041908 1.914652)
			(end -0.939546 1.914652)
			(stroke
				(width 0.0127)
				(type default)
			)
			(layer "F.SilkS")
		)
		(fp_line
			(start -1.051306 1.92405)
			(end -0.929894 1.92405)
			(stroke
				(width 0.0127)
				(type default)
			)
			(layer "F.SilkS")
		)
		(fp_line
			(start -1.060958 1.933702)
			(end -0.920496 1.933702)
			(stroke
				(width 0.0127)
				(type default)
			)
			(layer "F.SilkS")
		)
		(fp_line
			(start -1.070356 1.9431)
			(end -0.910844 1.9431)
			(stroke
				(width 0.0127)
				(type default)
			)
			(layer "F.SilkS")
		)
		(fp_line
			(start -1.080008 1.952752)
			(end -0.901446 1.952752)
			(stroke
				(width 0.0127)
				(type default)
			)
			(layer "F.SilkS")
		)
		(fp_line
			(start -1.089406 1.96215)
			(end -0.891794 1.96215)
			(stroke
				(width 0.0127)
				(type default)
			)
			(layer "F.SilkS")
		)
		(fp_line
			(start -1.099058 1.971802)
			(end -0.882396 1.971802)
			(stroke
				(width 0.0127)
				(type default)
			)
			(layer "F.SilkS")
		)
		(fp_line
			(start -1.108456 1.9812)
			(end -0.872744 1.9812)
			(stroke
				(width 0.0127)
				(type default)
			)
			(layer "F.SilkS")
		)
		(fp_line
			(start -1.118108 1.990852)
			(end -0.863346 1.990852)
			(stroke
				(width 0.0127)
				(type default)
			)
			(layer "F.SilkS")
		)
		(fp_line
			(start -1.127506 2.00025)
			(end -0.853694 2.00025)
			(stroke
				(width 0.0127)
				(type default)
			)
			(layer "F.SilkS")
		)
		(fp_line
			(start -1.137158 2.009902)
			(end -0.844296 2.009902)
			(stroke
				(width 0.0127)
				(type default)
			)
			(layer "F.SilkS")
		)
		(fp_line
			(start -1.146556 2.0193)
			(end -0.834644 2.0193)
			(stroke
				(width 0.0127)
				(type default)
			)
			(layer "F.SilkS")
		)
		(fp_line
			(start -1.156208 2.028952)
			(end -0.825246 2.028952)
			(stroke
				(width 0.0127)
				(type default)
			)
			(layer "F.SilkS")
		)
		(fp_line
			(start -1.165606 2.03835)
			(end -0.815594 2.03835)
			(stroke
				(width 0.0127)
				(type default)
			)
			(layer "F.SilkS")
		)
		(fp_line
			(start -1.175258 2.048002)
			(end -0.806196 2.048002)
			(stroke
				(width 0.0127)
				(type default)
			)
			(layer "F.SilkS")
		)
		(fp_line
			(start -1.184656 2.0574)
			(end -0.796544 2.0574)
			(stroke
				(width 0.0127)
				(type default)
			)
			(layer "F.SilkS")
		)
		(fp_line
			(start -1.194308 2.067052)
			(end -0.787146 2.067052)
			(stroke
				(width 0.0127)
				(type default)
			)
			(layer "F.SilkS")
		)
		(fp_line
			(start -1.203706 2.07645)
			(end -0.777494 2.07645)
			(stroke
				(width 0.0127)
				(type default)
			)
			(layer "F.SilkS")
		)
		(fp_line
			(start -1.213358 2.086102)
			(end -0.768096 2.086102)
			(stroke
				(width 0.0127)
				(type default)
			)
			(layer "F.SilkS")
		)
		(fp_line
			(start -1.222756 2.0955)
			(end -0.758444 2.0955)
			(stroke
				(width 0.0127)
				(type default)
			)
			(layer "F.SilkS")
		)
		(fp_line
			(start -1.232408 2.105152)
			(end -0.749046 2.105152)
			(stroke
				(width 0.0127)
				(type default)
			)
			(layer "F.SilkS")
		)
		(fp_line
			(start -1.241806 2.11455)
			(end -0.739394 2.11455)
			(stroke
				(width 0.0127)
				(type default)
			)
			(layer "F.SilkS")
		)
		(fp_line
			(start -1.251458 2.124202)
			(end -0.729996 2.124202)
			(stroke
				(width 0.0127)
				(type default)
			)
			(layer "F.SilkS")
		)
		(fp_line
			(start -1.260856 2.1336)
			(end -0.720344 2.1336)
			(stroke
				(width 0.0127)
				(type default)
			)
			(layer "F.SilkS")
		)
		(fp_line
			(start -1.279144 2.15265)
			(end -0.701294 2.15265)
			(stroke
				(width 0.0127)
				(type default)
			)
			(layer "F.SilkS")
		)
		(fp_line
			(start -1.279398 2.152142)
			(end -0.9906 1.86309)
			(stroke
				(width 0.0127)
				(type default)
			)
			(layer "F.SilkS")
		)
		(fp_line
			(start -1.651 1.778)
			(end 1.651 1.778)
			(stroke
				(width 0.1524)
				(type default)
			)
			(layer "F.SilkS")
		)
		(fp_line
			(start -1.651 -1.778)
			(end -1.651 1.778)
			(stroke
				(width 0.1524)
				(type default)
			)
			(layer "F.SilkS")
		)
		(fp_line
			(start -1.7526 1.8796)
			(end -1.7526 0.9906)
			(stroke
				(width 0.3302)
				(type default)
			)
			(layer "F.SilkS")
		)
		(fp_poly
			(pts
				(xy -1.285748 2.159) (xy -1.285748 1.8796) (xy -1.778 1.8796) (xy -1.778 -1.8796) (xy 1.778 -1.8796)
				(xy 1.778 1.8796) (xy -0.694944 1.8796) (xy -0.694944 2.159)
			)
			(stroke
				(width 0)
				(type default)
			)
			(fill no)
			(layer "F.CrtYd")
		)
		(fp_poly
			(pts
				(xy -1.285748 2.159) (xy -1.285748 1.8796) (xy -1.778 1.8796) (xy -1.778 -1.8796) (xy 1.778 -1.8796)
				(xy 1.778 1.8796) (xy -0.694944 1.8796) (xy -0.694944 2.159)
			)
			(stroke
				(width 0)
				(type default)
			)
			(fill no)
			(layer "F.Fab")
		)
		(pad "1" smd rect
			(at -0.98425 0.9525 180)
			(size 0.762 1.143)
			(layers "F.Cu" "F.Mask" "F.Paste")
			(net "LED_DR_LED5_B")
		)
		(pad "2" smd rect
			(at 0.98425 0.9525 180)
			(size 0.762 1.143)
			(layers "F.Cu" "F.Mask" "F.Paste")
			(net "GND")
		)
		(pad "3" smd rect
			(at 0 -0.9525 180)
			(size 0.762 1.143)
			(layers "F.Cu" "F.Mask" "F.Paste")
			(net "LED_DR_LED5_BLUE")
		)
	)
	(footprint ""
		(layer "F.Cu")
		(at 43.9166 -101.0666 90)
		(property "Reference" "TC8"
			(at 0 0 90)
			(layer "F.SilkS")
			(hide yes)
			(effects
				(font
					(size 1.27 1.27)
				)
			)
		)
		(property "Value" "ST15U25VDM-1-GP"
			(at 0 -9.6012 90)
			(unlocked yes)
			(layer "F.Fab")
			(hide yes)
			(effects
				(font
					(size 1.016 1.016)
					(thickness 0.1524)
				)
			)
		)
		(property "Device Type" "CT7343H79"
			(at 0 -11.1252 90)
			(unlocked yes)
			(layer "F.Fab")
			(hide yes)
			(effects
				(font
					(size 1.016 1.016)
					(thickness 0.1524)
				)
			)
		)
		(duplicate_pad_numbers_are_jumpers no)
		(fp_line
			(start 2.286 -4.8768)
			(end -2.286 -4.8768)
			(stroke
				(width 0.1524)
				(type default)
			)
			(layer "F.SilkS")
		)
		(fp_line
			(start -2.286 -4.8768)
			(end -2.286 -2.032)
			(stroke
				(width 0.1524)
				(type default)
			)
			(layer "F.SilkS")
		)
		(fp_line
			(start 2.1082 -4.699)
			(end -2.1082 -4.699)
			(stroke
				(width 0.508)
				(type default)
			)
			(layer "F.SilkS")
		)
		(fp_line
			(start 2.286 -2.032)
			(end 2.286 -4.8768)
			(stroke
				(width 0.1524)
				(type default)
			)
			(layer "F.SilkS")
		)
		(fp_line
			(start 2.286 2.032)
			(end 2.286 4.8768)
			(stroke
				(width 0.1524)
				(type default)
			)
			(layer "F.SilkS")
		)
		(fp_line
			(start 2.286 4.8768)
			(end -2.286 4.8768)
			(stroke
				(width 0.1524)
				(type default)
			)
			(layer "F.SilkS")
		)
		(fp_line
			(start -2.286 4.8768)
			(end -2.286 2.032)
			(stroke
				(width 0.1524)
				(type default)
			)
			(layer "F.SilkS")
		)
		(fp_rect
			(start -2.1463 3.6449)
			(end 2.1463 -3.6449)
			(stroke
				(width 0)
				(type default)
			)
			(fill no)
			(layer "F.CrtYd")
		)
		(fp_poly
			(pts
				(xy -2.54 4.953) (xy -2.54 4.2926) (xy -3.81 4.2926) (xy -3.81 -4.2926) (xy -2.54 -4.2926) (xy -2.54 -4.953)
				(xy 2.54 -4.953) (xy 2.54 -4.2926) (xy 3.81 -4.2926) (xy 3.81 -1.6256) (xy 2.1463 -1.6256) (xy 2.1463 -3.6449)
				(xy -2.1463 -3.6449) (xy -2.1463 3.6449) (xy 2.1463 3.6449) (xy 2.1463 -1.6129) (xy 3.81 -1.6129)
				(xy 3.81 4.2926) (xy 2.54 4.2926) (xy 2.54 4.953)
			)
			(stroke
				(width 0)
				(type default)
			)
			(fill no)
			(layer "F.CrtYd")
		)
		(fp_rect
			(start 2.54 4.2926)
			(end 3.81 -4.2926)
			(stroke
				(width 0)
				(type default)
			)
			(fill no)
			(layer "F.Fab")
		)
		(fp_rect
			(start -3.81 4.2926)
			(end -2.54 -4.2926)
			(stroke
				(width 0)
				(type default)
			)
			(fill no)
			(layer "F.Fab")
		)
		(fp_rect
			(start -2.54 4.953)
			(end 2.54 -4.953)
			(stroke
				(width 0)
				(type default)
			)
			(fill no)
			(layer "F.Fab")
		)
		(pad "1" smd rect
			(at 0 -3.1496 90)
			(size 2.413 2.286)
			(layers "F.Cu" "F.Mask" "F.Paste")
			(net "P12VL")
		)
		(pad "2" smd rect
			(at 0 3.1496 90)
			(size 2.413 2.286)
			(layers "F.Cu" "F.Mask" "F.Paste")
			(net "GND")
		)
		(zone
			(layer "F.Cu")
			(hatch none 0.5)
			(connect_pads
				(clearance 0)
			)
			(min_thickness 0.25)
			(keepout
				(tracks allowed)
				(vias not_allowed)
				(pads allowed)
				(copperpour not_allowed)
				(footprints allowed)
			)
			(placement
				(enabled no)
				(sheetname "")
			)
			(fill
				(thermal_gap 0.5)
				(thermal_bridge_width 0.5)
				(island_removal_mode 0)
			)
			(polygon
				(pts
					(xy 42.2275 -102.5779) (xy 39.3192 -102.5779) (xy 39.3192 -99.5553) (xy 42.2148 -99.5553) (xy 42.545 -99.5553)
					(xy 42.545 -102.5779)
				)
			)
		)
		(zone
			(layer "F.Cu")
			(hatch none 0.5)
			(connect_pads
				(clearance 0)
			)
			(min_thickness 0.25)
			(keepout
				(tracks allowed)
				(vias not_allowed)
				(pads allowed)
				(copperpour not_allowed)
				(footprints allowed)
			)
			(placement
				(enabled no)
				(sheetname "")
			)
			(fill
				(thermal_gap 0.5)
				(thermal_bridge_width 0.5)
				(island_removal_mode 0)
			)
			(polygon
				(pts
					(xy 48.514 -99.5553) (xy 48.514 -102.5779) (xy 45.6184 -102.5779) (xy 45.2882 -102.5779) (xy 45.2882 -99.5553)
					(xy 45.6184 -99.5553)
				)
			)
		)
	)
)
